(kicad_pcb
	(version 20260206)
	(generator "pcbnew")
	(generator_version "10.0")
	(general
		(thickness 0.77096)
		(legacy_teardrops no)
	)
	(paper "A4")
	(title_block
		(title "gnss-m2-neo-m9n — M2_NEO-M9N_MODULE.PcbDoc")
		(comment 1 "Time Appliance Project (Time Card) / footprints 1-12 of 40")
	)
	(layers
		(0 "F.Cu" signal "L01-Top Layer")
		(4 "In1.Cu" signal "L02-Inner Layer")
		(6 "In2.Cu" signal "L03-Inner Layer")
		(2 "B.Cu" signal "L04-Bottom Layer")
		(9 "F.Adhes" user "F.Adhesive")
		(11 "B.Adhes" user "B.Adhesive")
		(13 "F.Paste" user "Top Paste")
		(15 "B.Paste" user "Bottom Paste")
		(5 "F.SilkS" user "Top Overlay")
		(7 "B.SilkS" user "Bottom Overlay")
		(1 "F.Mask" user "Top Solder")
		(3 "B.Mask" user "Bottom Solder")
		(17 "Dwgs.User" user "User.Drawings")
		(19 "Cmts.User" user "User.Comments")
		(21 "Eco1.User" user "User.Eco1")
		(23 "Eco2.User" user "User.Eco2")
		(25 "Edge.Cuts" user)
		(27 "Margin" user)
		(31 "F.CrtYd" user "Top Courtyard")
		(29 "B.CrtYd" user "Bottom Courtyard")
		(35 "F.Fab" user "Top Component Outline")
		(33 "B.Fab" user "Bottom Component Outline 2")
	)
	(footprint "MyLibrary:TP1MM"
		(layer "F.Cu")
		(at 152.501105 93.3036)
		(property "Reference" "TP5"
			(at -0.522195 -1.177557 0)
			(unlocked yes)
			(layer "F.SilkS")
			(effects
				(font
					(size 0.635 0.635)
					(thickness 0.1778)
				)
			)
		)
		(property "Value" "1MM"
			(at -2.092783 1.790085 270)
			(unlocked yes)
			(layer "F.SilkS")
			(hide yes)
			(effects
				(font
					(size 0.635 0.635)
					(thickness 0.1778)
				)
			)
		)
		(sheetname "01-M2_NEO-M9N_MODULE")
		(sheetfile "01-M2_NEO-M9N_MODULE.kicad_sch")
		(duplicate_pad_numbers_are_jumpers no)
		(pad "1" smd circle
			(at 0 0)
			(size 1 1)
			(layers "F.Cu" "F.Mask" "F.Paste")
			(net "EXTIN")
			(solder_paste_margin -100)
			(thermal_bridge_angle 90)
		)
	)
	(footprint "Vault:RESC1005X40X25NL05T10"
		(layer "F.Cu")
		(at 141.701105 112.7036 90)
		(property "Reference" "R15"
			(at 0 -2.099924 90)
			(unlocked yes)
			(layer "F.SilkS")
			(effects
				(font
					(face "Arial")
					(size 0.48006 0.48006)
					(thickness 0.254)
				)
			)
		)
		(property "Value" "0_5%_0402"
			(at -2.759202 6.766925 0)
			(unlocked yes)
			(layer "F.SilkS")
			(hide yes)
			(effects
				(font
					(size 1.524 1.524)
					(thickness 0.254)
				)
			)
		)
		(sheetname "02-M2_GoldFingers")
		(sheetfile "02-M2_GoldFingers.kicad_sch")
		(duplicate_pad_numbers_are_jumpers no)
		(fp_line
			(start 0.9 -0.45)
			(end 0.9 0.45)
			(stroke
				(width 0.05)
				(type solid)
			)
			(layer "F.CrtYd")
		)
		(fp_line
			(start -0.9 -0.45)
			(end 0.9 -0.45)
			(stroke
				(width 0.05)
				(type solid)
			)
			(layer "F.CrtYd")
		)
		(fp_line
			(start -0.9 -0.45)
			(end -0.9 0.45)
			(stroke
				(width 0.05)
				(type solid)
			)
			(layer "F.CrtYd")
		)
		(fp_line
			(start 0 -0.275)
			(end 0 0.275)
			(stroke
				(width 0.1)
				(type solid)
			)
			(layer "F.CrtYd")
		)
		(fp_line
			(start -0.275 0)
			(end 0.275 0)
			(stroke
				(width 0.1)
				(type solid)
			)
			(layer "F.CrtYd")
		)
		(fp_line
			(start -0.9 0.45)
			(end 0.9 0.45)
			(stroke
				(width 0.05)
				(type solid)
			)
			(layer "F.CrtYd")
		)
		(pad "1" smd rect
			(at -0.425 0 180)
			(size 0.55 0.6)
			(layers "F.Cu" "F.Mask" "F.Paste")
			(net "NetJ1_46")
		)
		(pad "2" smd rect
			(at 0.425 0 180)
			(size 0.55 0.6)
			(layers "F.Cu" "F.Mask" "F.Paste")
			(net "TP1")
		)
	)
	(footprint "MyLibrary:c0402"
		(layer "F.Cu")
		(at 154.901105 112.4036 180)
		(property "Reference" "C3"
			(at -2.030895 -0.022443 0)
			(unlocked yes)
			(layer "F.SilkS")
			(effects
				(font
					(size 0.635 0.635)
					(thickness 0.1778)
				)
			)
		)
		(property "Value" "10nF 50V 0402"
			(at 5.065455 2.118183 180)
			(unlocked yes)
			(layer "F.SilkS")
			(hide yes)
			(effects
				(font
					(size 0.635 0.635)
					(thickness 0.1778)
				)
			)
		)
		(sheetname "01-M2_NEO-M9N_MODULE")
		(sheetfile "01-M2_NEO-M9N_MODULE.kicad_sch")
		(duplicate_pad_numbers_are_jumpers no)
		(fp_line
			(start 0.9906 0.4826)
			(end -0.9906 0.4826)
			(stroke
				(width 0.1778)
				(type solid)
			)
			(layer "F.SilkS")
		)
		(fp_line
			(start 0.9906 -0.4826)
			(end 0.9906 0.4826)
			(stroke
				(width 0.1778)
				(type solid)
			)
			(layer "F.SilkS")
		)
		(fp_line
			(start 0.9906 -0.4826)
			(end -0.9906 -0.4826)
			(stroke
				(width 0.1778)
				(type solid)
			)
			(layer "F.SilkS")
		)
		(fp_line
			(start -0.9906 -0.4826)
			(end -0.9906 0.4826)
			(stroke
				(width 0.1778)
				(type solid)
			)
			(layer "F.SilkS")
		)
		(pad "1" smd rect
			(at -0.5 0 180)
			(size 0.5 0.5)
			(layers "F.Cu" "F.Mask" "F.Paste")
			(net "GND")
		)
		(pad "2" smd rect
			(at 0.5 0 180)
			(size 0.5 0.5)
			(layers "F.Cu" "F.Mask" "F.Paste")
			(net "+3V3")
		)
	)
	(footprint "MyLibrary:r0402"
		(layer "F.Cu")
		(at 144.101105 119.1036 -90)
		(property "Reference" "R5"
			(at -1.873665 0.022443 270)
			(unlocked yes)
			(layer "F.SilkS")
			(effects
				(font
					(size 0.635 0.635)
					(thickness 0.1778)
				)
			)
		)
		(property "Value" "0 ohm 0402"
			(at 2.907155 2.168983 270)
			(unlocked yes)
			(layer "F.SilkS")
			(hide yes)
			(effects
				(font
					(size 0.635 0.635)
					(thickness 0.1778)
				)
			)
		)
		(sheetname "01-M2_NEO-M9N_MODULE")
		(sheetfile "01-M2_NEO-M9N_MODULE.kicad_sch")
		(duplicate_pad_numbers_are_jumpers no)
		(fp_line
			(start -0.9906 0.5334)
			(end -0.9906 -0.5334)
			(stroke
				(width 0.1778)
				(type solid)
			)
			(layer "F.SilkS")
		)
		(fp_line
			(start 0.9906 0.5334)
			(end -0.9906 0.5334)
			(stroke
				(width 0.1778)
				(type solid)
			)
			(layer "F.SilkS")
		)
		(fp_line
			(start 0.9906 0.5334)
			(end 0.9906 -0.5334)
			(stroke
				(width 0.1778)
				(type solid)
			)
			(layer "F.SilkS")
		)
		(fp_line
			(start 0.9906 -0.5334)
			(end -0.9906 -0.5334)
			(stroke
				(width 0.1778)
				(type solid)
			)
			(layer "F.SilkS")
		)
		(pad "1" smd rect
			(at -0.5 0 270)
			(size 0.5 0.6)
			(layers "F.Cu" "F.Mask" "F.Paste")
			(net "RX_GPS")
		)
		(pad "2" smd rect
			(at 0.5 0 270)
			(size 0.5 0.6)
			(layers "F.Cu" "F.Mask" "F.Paste")
			(net "RX_GPS_CONN")
		)
	)
	(footprint "Vault:RESC1005X40X25NL05T10"
		(layer "F.Cu")
		(at 141.301105 119.1036 -90)
		(property "Reference" "R12"
			(at -2.246 0.126931 270)
			(unlocked yes)
			(layer "F.SilkS")
			(effects
				(font
					(size 0.762 0.762)
					(thickness 0.254)
				)
			)
		)
		(property "Value" "0_5%_0402"
			(at -2.759192 6.766925 180)
			(unlocked yes)
			(layer "F.SilkS")
			(hide yes)
			(effects
				(font
					(size 1.524 1.524)
					(thickness 0.254)
				)
			)
		)
		(sheetname "02-M2_GoldFingers")
		(sheetfile "02-M2_GoldFingers.kicad_sch")
		(duplicate_pad_numbers_are_jumpers no)
		(fp_line
			(start -0.9 0.45)
			(end -0.9 -0.45)
			(stroke
				(width 0.05)
				(type solid)
			)
			(layer "F.CrtYd")
		)
		(fp_line
			(start 0.9 0.45)
			(end -0.9 0.45)
			(stroke
				(width 0.05)
				(type solid)
			)
			(layer "F.CrtYd")
		)
		(fp_line
			(start 0.9 0.45)
			(end 0.9 -0.45)
			(stroke
				(width 0.05)
				(type solid)
			)
			(layer "F.CrtYd")
		)
		(fp_line
			(start 0 0.275)
			(end 0 -0.275)
			(stroke
				(width 0.1)
				(type solid)
			)
			(layer "F.CrtYd")
		)
		(fp_line
			(start 0.275 0)
			(end -0.275 0)
			(stroke
				(width 0.1)
				(type solid)
			)
			(layer "F.CrtYd")
		)
		(fp_line
			(start 0.9 -0.45)
			(end -0.9 -0.45)
			(stroke
				(width 0.05)
				(type solid)
			)
			(layer "F.CrtYd")
		)
		(pad "1" smd rect
			(at -0.425 0)
			(size 0.55 0.6)
			(layers "F.Cu" "F.Mask" "F.Paste")
			(net "RST_GPS")
		)
		(pad "2" smd rect
			(at 0.425 0)
			(size 0.55 0.6)
			(layers "F.Cu" "F.Mask" "F.Paste")
			(net "NetJ1_67")
		)
	)
	(footprint "MyLibrary:c0402"
		(layer "F.Cu")
		(at 144.001105 90.0036 180)
		(property "Reference" "C5"
			(at -0.182795 1.077557 0)
			(unlocked yes)
			(layer "F.SilkS")
			(effects
				(font
					(size 0.635 0.635)
					(thickness 0.1778)
				)
			)
		)
		(property "Value" "10nF 50V 0402"
			(at 5.065455 2.118183 180)
			(unlocked yes)
			(layer "F.SilkS")
			(hide yes)
			(effects
				(font
					(size 0.635 0.635)
					(thickness 0.1778)
				)
			)
		)
		(sheetname "01-M2_NEO-M9N_MODULE")
		(sheetfile "01-M2_NEO-M9N_MODULE.kicad_sch")
		(duplicate_pad_numbers_are_jumpers no)
		(fp_line
			(start 0.9906 0.4826)
			(end -0.9906 0.4826)
			(stroke
				(width 0.1778)
				(type solid)
			)
			(layer "F.SilkS")
		)
		(fp_line
			(start 0.9906 -0.4826)
			(end 0.9906 0.4826)
			(stroke
				(width 0.1778)
				(type solid)
			)
			(layer "F.SilkS")
		)
		(fp_line
			(start 0.9906 -0.4826)
			(end -0.9906 -0.4826)
			(stroke
				(width 0.1778)
				(type solid)
			)
			(layer "F.SilkS")
		)
		(fp_line
			(start -0.9906 -0.4826)
			(end -0.9906 0.4826)
			(stroke
				(width 0.1778)
				(type solid)
			)
			(layer "F.SilkS")
		)
		(pad "1" smd rect
			(at -0.5 0 180)
			(size 0.5 0.5)
			(layers "F.Cu" "F.Mask" "F.Paste")
			(net "GND")
		)
		(pad "2" smd rect
			(at 0.5 0 180)
			(size 0.5 0.5)
			(layers "F.Cu" "F.Mask" "F.Paste")
			(net "NetC5_2")
		)
	)
	(footprint "Vault:FP-GRM31C-0_2-e0_3_0_8-IPC_C"
		(layer "F.Cu")
		(at 154.801105 114.1036)
		(property "Reference" "C6"
			(at -2.646005 0.126931 0)
			(unlocked yes)
			(layer "F.SilkS")
			(effects
				(font
					(size 0.762 0.762)
					(thickness 0.254)
				)
			)
		)
		(property "Value" "47uF_6.3V_1206"
			(at 8.620015 2.683002 0)
			(unlocked yes)
			(layer "F.SilkS")
			(hide yes)
			(effects
				(font
					(size 1.524 1.524)
					(thickness 0.254)
				)
			)
		)
		(sheetname "02-M2_GoldFingers")
		(sheetfile "02-M2_GoldFingers.kicad_sch")
		(duplicate_pad_numbers_are_jumpers no)
		(fp_line
			(start -0.39846 -0.9)
			(end 0.39847 -0.9)
			(stroke
				(width 0.2)
				(type solid)
			)
			(layer "F.SilkS")
		)
		(fp_line
			(start -0.39846 0.9)
			(end 0.39847 0.9)
			(stroke
				(width 0.2)
				(type solid)
			)
			(layer "F.SilkS")
		)
		(fp_line
			(start -1.9531 -1)
			(end 1.9531 -1)
			(stroke
				(width 0.2)
				(type solid)
			)
			(layer "F.CrtYd")
		)
		(fp_line
			(start -1.9531 1)
			(end -1.9531 -1)
			(stroke
				(width 0.2)
				(type solid)
			)
			(layer "F.CrtYd")
		)
		(fp_line
			(start -1.9531 1)
			(end 1.9531 1)
			(stroke
				(width 0.2)
				(type solid)
			)
			(layer "F.CrtYd")
		)
		(fp_line
			(start 1.9531 1)
			(end 1.9531 -1)
			(stroke
				(width 0.2)
				(type solid)
			)
			(layer "F.CrtYd")
		)
		(fp_line
			(start -1.9531 -1)
			(end 1.9531 -1)
			(stroke
				(width 0.2)
				(type solid)
			)
			(layer "F.Fab")
		)
		(fp_line
			(start -1.9531 1)
			(end -1.9531 -1)
			(stroke
				(width 0.2)
				(type solid)
			)
			(layer "F.Fab")
		)
		(fp_line
			(start -1.9531 1)
			(end 1.9531 1)
			(stroke
				(width 0.2)
				(type solid)
			)
			(layer "F.Fab")
		)
		(fp_line
			(start -0.5 0)
			(end 0.5 0)
			(stroke
				(width 0.1)
				(type solid)
			)
			(layer "F.Fab")
		)
		(fp_line
			(start 0 0.5)
			(end 0 -0.5)
			(stroke
				(width 0.1)
				(type solid)
			)
			(layer "F.Fab")
		)
		(fp_line
			(start 1.9531 1)
			(end 1.9531 -1)
			(stroke
				(width 0.2)
				(type solid)
			)
			(layer "F.Fab")
		)
		(fp_text user "${REFERENCE}"
			(at -0.00001 0.09602 0)
			(unlocked yes)
			(layer "F.Fab")
			(effects
				(font
					(face "Arial")
					(size 0.63 0.63)
					(thickness 0.1)
				)
				(justify left bottom)
			)
		)
		(pad "1" smd rect
			(at -1.27578 0)
			(size 1.15464 1.7062)
			(layers "F.Cu" "F.Mask" "F.Paste")
			(net "+3V3")
			(solder_mask_margin 0)
			(solder_paste_margin 0)
		)
		(pad "2" smd rect
			(at 1.27578 0)
			(size 1.15464 1.7062)
			(layers "F.Cu" "F.Mask" "F.Paste")
			(net "GND")
			(solder_mask_margin 0)
			(solder_paste_margin 0)
		)
	)
	(footprint "MyLibrary:c0402"
		(layer "F.Cu")
		(at 154.901105 110.0036 180)
		(property "Reference" "C1"
			(at -1.977795 -0.022443 0)
			(unlocked yes)
			(layer "F.SilkS")
			(effects
				(font
					(size 0.635 0.635)
					(thickness 0.1778)
				)
			)
		)
		(property "Value" "1uF 6V3 0402"
			(at 4.3037 2.118183 180)
			(unlocked yes)
			(layer "F.SilkS")
			(hide yes)
			(effects
				(font
					(size 0.635 0.635)
					(thickness 0.1778)
				)
			)
		)
		(sheetname "01-M2_NEO-M9N_MODULE")
		(sheetfile "01-M2_NEO-M9N_MODULE.kicad_sch")
		(duplicate_pad_numbers_are_jumpers no)
		(fp_line
			(start 0.9906 0.4826)
			(end -0.9906 0.4826)
			(stroke
				(width 0.1778)
				(type solid)
			)
			(layer "F.SilkS")
		)
		(fp_line
			(start 0.9906 -0.4826)
			(end 0.9906 0.4826)
			(stroke
				(width 0.1778)
				(type solid)
			)
			(layer "F.SilkS")
		)
		(fp_line
			(start 0.9906 -0.4826)
			(end -0.9906 -0.4826)
			(stroke
				(width 0.1778)
				(type solid)
			)
			(layer "F.SilkS")
		)
		(fp_line
			(start -0.9906 -0.4826)
			(end -0.9906 0.4826)
			(stroke
				(width 0.1778)
				(type solid)
			)
			(layer "F.SilkS")
		)
		(pad "1" smd rect
			(at -0.5 0 180)
			(size 0.5 0.5)
			(layers "F.Cu" "F.Mask" "F.Paste")
			(net "GND")
		)
		(pad "2" smd rect
			(at 0.5 0 180)
			(size 0.5 0.5)
			(layers "F.Cu" "F.Mask" "F.Paste")
			(net "+3V3")
		)
	)
	(footprint "MyLibrary:TP1MM"
		(layer "F.Cu")
		(at 155.201105 93.7036)
		(property "Reference" "TP1"
			(at 1.677805 0.292633 0)
			(unlocked yes)
			(layer "F.SilkS")
			(effects
				(font
					(size 0.635 0.635)
					(thickness 0.1778)
				)
			)
		)
		(property "Value" "1MM"
			(at -2.092783 1.790085 270)
			(unlocked yes)
			(layer "F.SilkS")
			(hide yes)
			(effects
				(font
					(size 0.635 0.635)
					(thickness 0.1778)
				)
			)
		)
		(sheetname "01-M2_NEO-M9N_MODULE")
		(sheetfile "01-M2_NEO-M9N_MODULE.kicad_sch")
		(duplicate_pad_numbers_are_jumpers no)
		(pad "1" smd circle
			(at 0 0)
			(size 1 1)
			(layers "F.Cu" "F.Mask" "F.Paste")
			(net "D_SEL")
			(solder_paste_margin -100)
			(thermal_bridge_angle 90)
		)
	)
	(footprint "MyLibrary:r0402"
		(layer "F.Cu")
		(at 154.001105 90.0036 180)
		(property "Reference" "R7"
			(at 0.622005 2.177557 0)
			(unlocked yes)
			(layer "F.SilkS")
			(effects
				(font
					(size 0.635 0.635)
					(thickness 0.178)
				)
			)
		)
		(property "Value" "0 ohm 0402"
			(at 6.79212 2.200402 180)
			(unlocked yes)
			(layer "F.SilkS")
			(hide yes)
			(effects
				(font
					(size 1.524 1.524)
					(thickness 0.254)
				)
			)
		)
		(sheetname "01-M2_NEO-M9N_MODULE")
		(sheetfile "01-M2_NEO-M9N_MODULE.kicad_sch")
		(duplicate_pad_numbers_are_jumpers no)
		(fp_line
			(start 0.9906 0.5334)
			(end -0.9906 0.5334)
			(stroke
				(width 0.1778)
				(type solid)
			)
			(layer "F.SilkS")
		)
		(fp_line
			(start 0.9906 -0.5334)
			(end 0.9906 0.5334)
			(stroke
				(width 0.1778)
				(type solid)
			)
			(layer "F.SilkS")
		)
		(fp_line
			(start 0.9906 -0.5334)
			(end -0.9906 -0.5334)
			(stroke
				(width 0.1778)
				(type solid)
			)
			(layer "F.SilkS")
		)
		(fp_line
			(start -0.9906 -0.5334)
			(end -0.9906 0.5334)
			(stroke
				(width 0.1778)
				(type solid)
			)
			(layer "F.SilkS")
		)
		(pad "1" smd rect
			(at -0.5 0 180)
			(size 0.5 0.6)
			(layers "F.Cu" "F.Mask" "F.Paste")
			(net "LNA_EN")
		)
		(pad "2" smd rect
			(at 0.5 0 180)
			(size 0.5 0.6)
			(layers "F.Cu" "F.Mask" "F.Paste")
			(net "NetQ1_1")
		)
	)
	(footprint "Vault:FP-U_FL-R-SMT-1_10-MFG"
		(layer "F.Cu")
		(at 140.901105 86.1036 180)
		(property "Reference" "J2"
			(at -3.064092 -0.477805 270)
			(unlocked yes)
			(layer "F.SilkS")
			(effects
				(font
					(size 1.016 1.016)
					(thickness 0.1778)
				)
			)
		)
		(property "Value" "U.FL-R-SMT-1(10)"
			(at 7.55289 12.938543 180)
			(unlocked yes)
			(layer "F.SilkS")
			(hide yes)
			(effects
				(font
					(size 0.635 0.635)
					(thickness 0.1778)
				)
			)
		)
		(sheetname "01-M2_NEO-M9N_MODULE")
		(sheetfile "01-M2_NEO-M9N_MODULE.kicad_sch")
		(duplicate_pad_numbers_are_jumpers no)
		(fp_line
			(start 0.575 1.375)
			(end -0.575 1.375)
			(stroke
				(width 0.2)
				(type solid)
			)
			(layer "F.SilkS")
		)
		(fp_rect
			(start 1.0499 1.00009)
			(end 1.9499 -0.99991)
			(stroke
				(width 0)
				(type default)
			)
			(fill yes)
			(layer "F.Paste")
		)
		(fp_rect
			(start -0.4 -1.09888)
			(end 0.39999 -1.94888)
			(stroke
				(width 0)
				(type default)
			)
			(fill yes)
			(layer "F.Paste")
		)
		(fp_rect
			(start -1.94989 0.99991)
			(end -1.04989 -1.00009)
			(stroke
				(width 0)
				(type default)
			)
			(fill yes)
			(layer "F.Paste")
		)
		(fp_line
			(start 2.1 1.475)
			(end -2.1 1.475)
			(stroke
				(width 0.2)
				(type solid)
			)
			(layer "F.CrtYd")
		)
		(fp_line
			(start 2.1 -2.15)
			(end 2.1 1.475)
			(stroke
				(width 0.2)
				(type solid)
			)
			(layer "F.CrtYd")
		)
		(fp_line
			(start 2.1 -2.15)
			(end -2.1 -2.15)
			(stroke
				(width 0.2)
				(type solid)
			)
			(layer "F.CrtYd")
		)
		(fp_line
			(start -2.1 -2.15)
			(end -2.1 1.475)
			(stroke
				(width 0.2)
				(type solid)
			)
			(layer "F.CrtYd")
		)
		(fp_line
			(start 2.1 1.475)
			(end -2.1 1.475)
			(stroke
				(width 0.2)
				(type solid)
			)
			(layer "F.Fab")
		)
		(fp_line
			(start 2.1 -2.15)
			(end 2.1 1.475)
			(stroke
				(width 0.2)
				(type solid)
			)
			(layer "F.Fab")
		)
		(fp_line
			(start 2.1 -2.15)
			(end -2.1 -2.15)
			(stroke
				(width 0.2)
				(type solid)
			)
			(layer "F.Fab")
		)
		(fp_line
			(start 0.54375 0)
			(end -0.54375 0)
			(stroke
				(width 0.1)
				(type solid)
			)
			(layer "F.Fab")
		)
		(fp_line
			(start 0 -0.54375)
			(end 0 0.54375)
			(stroke
				(width 0.1)
				(type solid)
			)
			(layer "F.Fab")
		)
		(fp_line
			(start -2.1 -2.15)
			(end -2.1 1.475)
			(stroke
				(width 0.2)
				(type solid)
			)
			(layer "F.Fab")
		)
		(fp_text user "${REFERENCE}"
			(at -0.00186 -0.24148 180)
			(unlocked yes)
			(layer "F.Fab")
			(effects
				(font
					(face "Arial")
					(size 0.63 0.63)
					(thickness 0.1)
				)
				(justify left bottom)
			)
		)
		(pad "1" smd rect
			(at 0 -1.525 180)
			(size 1 1.05)
			(layers "F.Cu" "F.Mask" "F.Paste")
			(net "RF_ANT")
			(solder_mask_margin 0)
			(solder_paste_margin -1000)
		)
		(pad "2" smd rect
			(at -1.475 0 180)
			(size 1.05 2.2)
			(layers "F.Cu" "F.Mask" "F.Paste")
			(net "GND")
			(solder_mask_margin 0)
			(solder_paste_margin -1000)
		)
		(pad "3" smd rect
			(at 1.475 0 180)
			(size 1.05 2.2)
			(layers "F.Cu" "F.Mask" "F.Paste")
			(net "GND")
			(solder_mask_margin 0)
			(solder_paste_margin -1000)
		)
	)
	(footprint "MyLibrary:TP1MM"
		(layer "F.Cu")
		(at 154.501105 88.5036)
		(property "Reference" "TP6"
			(at 1.112805 -1.077557 0)
			(unlocked yes)
			(layer "F.SilkS")
			(effects
				(font
					(size 0.635 0.635)
					(thickness 0.1778)
				)
			)
		)
		(property "Value" "1MM"
			(at -2.092793 1.790085 270)
			(unlocked yes)
			(layer "F.SilkS")
			(hide yes)
			(effects
				(font
					(size 0.635 0.635)
					(thickness 0.1778)
				)
			)
		)
		(sheetname "01-M2_NEO-M9N_MODULE")
		(sheetfile "01-M2_NEO-M9N_MODULE.kicad_sch")
		(duplicate_pad_numbers_are_jumpers no)
		(pad "1" smd circle
			(at 0 0)
			(size 1 1)
			(layers "F.Cu" "F.Mask" "F.Paste")
			(net "LNA_EN")
			(solder_paste_margin -100)
			(thermal_bridge_angle 90)
		)
	)
)
